# T6G (Grand Teton) — schematic netlist excerpt (pin names and nets, part order shuffled) for the footprints in the layout excerpt that follows; sources: Cadence DE-HDL packaged netlist, KiCad conversion of 04192023_DAF0TMB3IC0_F0TG_MB_C_brd_V02_OCP.brd

J68  SCONN288_DDR506112002KQ  IO  pkg DDR288S_1-1VXC  page 95
  VIN_BULK0  = P12V_MEM_CPU0
  RFU0  = NC
  VIN_MGMT  = P3V3_AUX
  HSCL  = I3C_SPD_DDRJ_CPU0_SCL
  HSDA  = I3C_SPD_DDRJ_CPU0_SDA
  VSS0  = GND
  DQ0_A  = M_J_CPU0_SA_DQ<0>
  VSS1  = GND
  DQ1_A  = M_J_CPU0_SA_DQ<1>
  VSS2  = GND
  DQS0_A_T  = M_J_CPU0_SA_DQS_DP<0>
  DQS0_A_C  = M_J_CPU0_SA_DQS_DN<0>
  VSS3  = GND
  DQ4_A  = M_J_CPU0_SA_DQ<4>
  VSS4  = GND
  DQ5_A  = M_J_CPU0_SA_DQ<5>
  VSS5  = GND
  DQ8_A  = M_J_CPU0_SA_DQ<8>
  VSS6  = GND
  DQ9_A  = M_J_CPU0_SA_DQ<9>
  VSS7  = GND
  DQS1_A_T  = M_J_CPU0_SA_DQS_DP<1>
  DQS1_A_C  = M_J_CPU0_SA_DQS_DN<1>
  VSS8  = GND
  DQ12_A  = M_J_CPU0_SA_DQ<12>
  VSS9  = GND
  DQ13_A  = M_J_CPU0_SA_DQ<13>
  VSS10  = GND
  DQ16_A  = M_J_CPU0_SA_DQ<16>
  VSS11  = GND
  DQ17_A  = M_J_CPU0_SA_DQ<17>
  VSS12  = GND
  DQS2_A_T  = M_J_CPU0_SA_DQS_DP<2>
  DQS2_A_C  = M_J_CPU0_SA_DQS_DN<2>
  VSS13  = GND
  DQ20_A  = M_J_CPU0_SA_DQ<20>
  VSS14  = GND
  DQ21_A  = M_J_CPU0_SA_DQ<21>
  VSS15  = GND
  DQ24_A  = M_J_CPU0_SA_DQ<24>
  VSS16  = GND
  DQ25_A  = M_J_CPU0_SA_DQ<25>
  VSS17  = GND
  DQS3_A_T  = M_J_CPU0_SA_DQS_DP<3>
  DQS3_A_C  = M_J_CPU0_SA_DQS_DN<3>
  VSS18  = GND
  DQ28_A  = M_J_CPU0_SA_DQ<28>
  VSS19  = GND
  DQ29_A  = M_J_CPU0_SA_DQ<29>
  VSS20  = GND
  CB0_A  = M_J_CPU0_SA_CB<0>
  VSS21  = GND
  CB1_A  = M_J_CPU0_SA_CB<1>
  VSS22  = GND
  DQS4_A_T  = M_J_CPU0_SA_DQS_DP<4>
  DQS4_A_C  = M_J_CPU0_SA_DQS_DN<4>
  VSS23  = GND
  CB4_A  = M_J_CPU0_SA_CB<4>
  VSS24  = GND
  CB5_A  = M_J_CPU0_SA_CB<5>
  VSS25  = GND
  ALERT_N  = M_J_CPU0_ALERT_N
  VSS26  = GND
  CS0_A_N  = M_J_CPU0_SA_CS_N<0>
  VSS27  = GND
  CA0_A  = M_J_CPU0_SA_CA<0>
  VSS28  = GND
  CA2_A  = M_J_CPU0_SA_CA<2>
  VSS29  = GND
  CA4_A  = M_J_CPU0_SA_CA<4>
  VSS30  = GND
  CA6_A  = M_J_CPU0_SA_CA<6>
  VSS31  = GND
  PAR_A  = M_J_CPU0_SA_PAR
  VSS32  = GND
  CA0_B  = M_J_CPU0_SB_CA<0>
  VSS33  = GND
  CA2_B  = M_J_CPU0_SB_CA<2>
  VSS34  = GND
  CA4_B  = M_J_CPU0_SB_CA<4>
  VSS35  = GND
  CA6_B  = M_J_CPU0_SB_CA<6>
  VSS36  = GND
  CS0_B_N  = M_J_CPU0_SB_CS_N<0>
  VSS37  = GND
  \lbd||rsp_a_n\  = M_J_CPU0_SA_RSP<0>
  \lbs||rsp_b_n\  = M_J_CPU0_SB_RSP<0>
  VSS38  = GND
  CB4_B  = M_J_CPU0_SB_CB<4>
  VSS39  = GND
  CB5_B  = M_J_CPU0_SB_CB<5>
  VSS40  = GND
  \dqs9_b_t||tdqs9_b_t||dbi4_b_n\  = M_J_CPU0_SB_DQS_DP<9>
  \dqs9_b_c||tdqs9_b_c\  = M_J_CPU0_SB_DQS_DN<9>
  VSS41  = GND
  CB0_B  = M_J_CPU0_SB_CB<0>
  VSS42  = GND
  CB1_B  = M_J_CPU0_SB_CB<1>
  VSS43  = GND
  DQ0_B  = M_J_CPU0_SB_DQ<0>
  VSS44  = GND
  DQ1_B  = M_J_CPU0_SB_DQ<1>
  VSS45  = GND
  DQS0_B_T  = M_J_CPU0_SB_DQS_DP<0>
  DQS0_B_C  = M_J_CPU0_SB_DQS_DN<0>
  VSS46  = GND
  DQ4_B  = M_J_CPU0_SB_DQ<4>
  VSS47  = GND
  DQ5_B  = M_J_CPU0_SB_DQ<5>
  VSS48  = GND
  DQ8_B  = M_J_CPU0_SB_DQ<8>
  VSS49  = GND
  DQ9_B  = M_J_CPU0_SB_DQ<9>
  VSS50  = GND
  DQS1_B_T  = M_J_CPU0_SB_DQS_DP<1>
  DQS1_B_C  = M_J_CPU0_SB_DQS_DN<1>
  VSS51  = GND
  DQ12_B  = M_J_CPU0_SB_DQ<12>
  VSS52  = GND
  DQ13_B  = M_J_CPU0_SB_DQ<13>
  VSS53  = GND
  DQ16_B  = M_J_CPU0_SB_DQ<16>
  VSS54  = GND
  DQ17_B  = M_J_CPU0_SB_DQ<17>
  VSS55  = GND
  DQS2_B_T  = M_J_CPU0_SB_DQS_DP<2>
  DQS2_B_C  = M_J_CPU0_SB_DQS_DN<2>
  VSS56  = GND
  DQ20_B  = M_J_CPU0_SB_DQ<20>
  VSS57  = GND
  DQ21_B  = M_J_CPU0_SB_DQ<21>
  VSS58  = GND
  DQ24_B  = M_J_CPU0_SB_DQ<24>
  VSS59  = GND
  DQ25_B  = M_J_CPU0_SB_DQ<25>
  VSS60  = GND
  DQS3_B_T  = M_J_CPU0_SB_DQS_DP<3>
  DQS3_B_C  = M_J_CPU0_SB_DQS_DN<3>
  VSS61  = GND
  DQ28_B  = M_J_CPU0_SB_DQ<28>
  VSS62  = GND
  DQ29_B  = M_J_CPU0_SB_DQ<29>
  VSS63  = GND
  RFU1  = NC
  VIN_BULK1  = P12V_MEM_CPU0
  VIN_BULK2  = P12V_MEM_CPU0
  \pwr_good||fail_n\  = PWRGD_CHJ_CPU0_DIMM
  HAS  = PD_CHJ_CPU0_DIMM_SAA
  RFU2  = NC
  RFU3  = NC
  VSS64  = GND
  DQ2_A  = M_J_CPU0_SA_DQ<2>
  VSS65  = GND
  DQ3_A  = M_J_CPU0_SA_DQ<3>
  VSS66  = GND
  \dqs5_a_c||tdqs5_a_c||dqs5_a_t||tdqs5_a_t\  = M_J_CPU0_SA_DQS_DN<5>
  \dqs5_a_t||tdqs5_a_t\  = M_J_CPU0_SA_DQS_DP<5>
  VSS67  = GND
  DQ6_A  = M_J_CPU0_SA_DQ<6>
  VSS68  = GND
  DQ7_A  = M_J_CPU0_SA_DQ<7>
  VSS69  = GND
  DQ10_A  = M_J_CPU0_SA_DQ<10>
  VSS70  = GND
  DQ11_A  = M_J_CPU0_SA_DQ<11>
  VSS71  = GND
  \dqs6_a_c||tdqs6_a_c||dqs6_a_t||tdqs6_a_t\  = M_J_CPU0_SA_DQS_DN<6>
  \dqs6_a_t||tdqs6_a_t\  = M_J_CPU0_SA_DQS_DP<6>
  VSS72  = GND
  DQ14_A  = M_J_CPU0_SA_DQ<14>
  VSS73  = GND
  DQ15_A  = M_J_CPU0_SA_DQ<15>
  VSS74  = GND
  DQ18_A  = M_J_CPU0_SA_DQ<18>
  VSS75  = GND
  DQ19_A  = M_J_CPU0_SA_DQ<19>
  VSS76  = GND
  \dqs7_a_c||tdqs7_a_c\  = M_J_CPU0_SA_DQS_DN<7>
  \dqs7_a_t||tdqs7_a_t\  = M_J_CPU0_SA_DQS_DP<7>
  VSS77  = GND
  DQ22_A  = M_J_CPU0_SA_DQ<22>
  VSS78  = GND
  DQ23_A  = M_J_CPU0_SA_DQ<23>
  VSS79  = GND
  DQ26_A  = M_J_CPU0_SA_DQ<26>
  VSS80  = GND
  DQ27_A  = M_J_CPU0_SA_DQ<27>
  VSS81  = GND
  \dqs8_a_c||tdqs8_a_c\  = M_J_CPU0_SA_DQS_DN<8>
  \dqs8_a_t||tdqs8_a_t\  = M_J_CPU0_SA_DQS_DP<8>
  VSS82  = GND
  DQ30_A  = M_J_CPU0_SA_DQ<30>
  VSS83  = GND
  DQ31_A  = M_J_CPU0_SA_DQ<31>
  VSS84  = GND
  CB2_A  = M_J_CPU0_SA_CB<2>
  VSS85  = GND
  CB3_A  = M_J_CPU0_SA_CB<3>
  VSS86  = GND
  \dqs9_a_c||tdqs9_a_c\  = M_J_CPU0_SA_DQS_DN<9>
  \dqs9_a_t||tdqs9_a_t\  = M_J_CPU0_SA_DQS_DP<9>
  VSS87  = GND
  CB6_A  = M_J_CPU0_SA_CB<6>
  VSS88  = GND
  CB7_A  = M_J_CPU0_SA_CB<7>
  VSS89  = GND
  RESET_N  = M_J_CPU0_RESET_N
  VSS90  = GND
  CS1_A_N  = M_J_CPU0_SA_CS_N<1>
  VSS91  = GND
  CA1_A  = M_J_CPU0_SA_CA<1>
  VSS92  = GND
  CA3_A  = M_J_CPU0_SA_CA<3>
  VSS93  = GND
  CA5_A  = M_J_CPU0_SA_CA<5>
  VSS94  = GND
  CK_T  = M_J_CPU0_CLK_DP<0>
  CK_C  = M_J_CPU0_CLK_DN<0>
  VSS95  = GND
  RFU4  = NC
  CA1_B  = M_J_CPU0_SB_CA<1>
  VSS96  = GND
  CA3_B  = M_J_CPU0_SB_CA<3>
  VSS97  = GND
  CA5_B  = M_J_CPU0_SB_CA<5>
  VSS98  = GND
  PAR_B  = M_J_CPU0_SB_PAR
  VSS99  = GND
  CS1_B_N  = M_J_CPU0_SB_CS_N<1>
  VSS100  = GND
  RFU5  = NC
  RFU6  = NC
  VSS101  = GND
  CB6_B  = M_J_CPU0_SB_CB<6>
  VSS102  = GND
  CB7_B  = M_J_CPU0_SB_CB<7>
  VSS103  = GND
  DQS4_B_C  = M_J_CPU0_SB_DQS_DN<4>
  DQS4_B_T  = M_J_CPU0_SB_DQS_DP<4>
  VSS104  = GND
  CB2_B  = M_J_CPU0_SB_CB<2>
  VSS105  = GND
  CB3_B  = M_J_CPU0_SB_CB<3>
  VSS106  = GND
  DQ2_B  = M_J_CPU0_SB_DQ<2>
  VSS107  = GND
  DQ3_B  = M_J_CPU0_SB_DQ<3>
  VSS108  = GND
  \dqs5_b_c||tdqs5_b_c\  = M_J_CPU0_SB_DQS_DN<5>
  \dqs5_b_t||tdqs5_b_t\  = M_J_CPU0_SB_DQS_DP<5>
  VSS109  = GND
  DQ6_B  = M_J_CPU0_SB_DQ<6>
  VSS110  = GND
  DQ7_B  = M_J_CPU0_SB_DQ<7>
  VSS111  = GND
  DQ10_B  = M_J_CPU0_SB_DQ<10>
  VSS112  = GND
  DQ11_B  = M_J_CPU0_SB_DQ<11>
  VSS113  = GND
  \dqs6_b_c||tdqs6_b_c\  = M_J_CPU0_SB_DQS_DN<6>
  \dqs6_b_t||tdqs6_b_t\  = M_J_CPU0_SB_DQS_DP<6>
  VSS114  = GND
  DQ14_B  = M_J_CPU0_SB_DQ<14>
  VSS115  = GND
  DQ15_B  = M_J_CPU0_SB_DQ<15>
  VSS116  = GND
  DQ18_B  = M_J_CPU0_SB_DQ<18>
  VSS117  = GND
  DQ19_B  = M_J_CPU0_SB_DQ<19>
  VSS118  = GND
  \dqs7_b_c||tdqs7_b_c\  = M_J_CPU0_SB_DQS_DN<7>
  \dqs7_b_t||tdqs7_b_t\  = M_J_CPU0_SB_DQS_DP<7>
  VSS119  = GND
  DQ22_B  = M_J_CPU0_SB_DQ<22>
  VSS120  = GND
  DQ23_B  = M_J_CPU0_SB_DQ<23>
  VSS121  = GND
  DQ26_B  = M_J_CPU0_SB_DQ<26>
  VSS122  = GND
  DQ27_B  = M_J_CPU0_SB_DQ<27>
  VSS123  = GND
  \dqs8_b_c||tdqs8_b_c\  = M_J_CPU0_SB_DQS_DN<8>
  \dqs8_b_t||tdqs8_b_t\  = M_J_CPU0_SB_DQS_DP<8>
  VSS124  = GND
  DQ30_B  = M_J_CPU0_SB_DQ<30>
  VSS125  = GND
  DQ31_B  = M_J_CPU0_SB_DQ<31>
  VSS126  = GND
  G1  = GND
  G2  = GND
  G3  = GND

(kicad_pcb
	(version 20260206)
	(generator "pcbnew")
	(generator_version "10.0")
	(general
		(thickness 1.6)
		(legacy_teardrops no)
	)
	(paper "A4")
	(title_block
		(title "04192023_DAF0TMB3IC0_F0TG_MB_C_brd_V02_OCP.brd")
		(comment 1 "Grand Teton / footprint 802 of 8354 (J68), pads 92-137 of 291")
	)
	(layers
		(0 "F.Cu" signal "TOP")
		(4 "In1.Cu" signal "GND")
		(6 "In2.Cu" signal "IN1")
		(8 "In3.Cu" signal "GND1")
		(10 "In4.Cu" signal "IN2")
		(12 "In5.Cu" signal "GND2")
		(14 "In6.Cu" signal "IN3")
		(16 "In7.Cu" signal "GND3")
		(18 "In8.Cu" signal "VCC")
		(20 "In9.Cu" signal "VCC1")
		(22 "In10.Cu" signal "GND4")
		(24 "In11.Cu" signal "IN4")
		(26 "In12.Cu" signal "GND5")
		(28 "In13.Cu" signal "IN5")
		(30 "In14.Cu" signal "GND6")
		(32 "In15.Cu" signal "IN6")
		(34 "In16.Cu" signal "GND7")
		(2 "B.Cu" signal "BOTTOM")
		(9 "F.Adhes" user "F.Adhesive")
		(11 "B.Adhes" user "B.Adhesive")
		(13 "F.Paste" user "Package Geometry/Pastemask Top")
		(15 "B.Paste" user "Package Geometry/Pastemask Bottom")
		(5 "F.SilkS" user "Ref Des/Silkscreen Top")
		(7 "B.SilkS" user "Ref Des/Silkscreen Bottom")
		(1 "F.Mask" user "Board Geometry/Soldermask Top")
		(3 "B.Mask" user "Board Geometry/Soldermask Bottom")
		(17 "Dwgs.User" user "User.Drawings")
		(19 "Cmts.User" user "User.Comments")
		(21 "Eco1.User" user "User.Eco1")
		(23 "Eco2.User" user "User.Eco2")
		(25 "Edge.Cuts" user "Board Geometry/Outline")
		(27 "Margin" user)
		(31 "F.CrtYd" user "Package Geometry/Place Bound Top")
		(29 "B.CrtYd" user "Package Geometry/Place Bound Bottom")
		(35 "F.Fab" user "Ref Des/Assembly Top")
		(33 "B.Fab" user "Ref Des/Assembly Bottom")
	)
	(footprint ""
		(layer "F.Cu")
		(at 437.05018 -255.560068 180)
		(property "Reference" "J68"
			(at 1.32334 -81.844388 0)
			(unlocked yes)
			(layer "F.SilkS")
			(effects
				(font
					(size 0.7874 0.5842)
					(thickness 0.1524)
				)
			)
		)
		(property "Value" ""
			(at 0 0 180)
			(layer "F.Fab")
			(effects
				(font
					(size 1.27 1.27)
				)
			)
		)
		(duplicate_pad_numbers_are_jumpers no)
		(pad "92" smd rect
			(at -2.050034 19.12493 90)
			(size 0.519938 1.4986)
			(layers "F.Cu" "F.Mask" "F.Paste")
			(net "GND")
		)
		(pad "93" smd rect
			(at -2.050034 19.975068 90)
			(size 0.519938 1.4986)
			(layers "F.Cu" "F.Mask" "F.Paste")
			(net "M_J_CPU0_SB_DQS_DP<9>")
		)
		(pad "94" smd rect
			(at -2.050034 20.824952 90)
			(size 0.519938 1.4986)
			(layers "F.Cu" "F.Mask" "F.Paste")
			(net "M_J_CPU0_SB_DQS_DN<9>")
		)
		(pad "95" smd rect
			(at -2.050034 21.67509 90)
			(size 0.519938 1.4986)
			(layers "F.Cu" "F.Mask" "F.Paste")
			(net "GND")
		)
		(pad "96" smd rect
			(at -2.050034 22.524974 90)
			(size 0.519938 1.4986)
			(layers "F.Cu" "F.Mask" "F.Paste")
			(net "M_J_CPU0_SB_CB<0>")
		)
		(pad "97" smd rect
			(at -2.050034 23.375112 90)
			(size 0.519938 1.4986)
			(layers "F.Cu" "F.Mask" "F.Paste")
			(net "GND")
		)
		(pad "98" smd rect
			(at -2.050034 24.224996 90)
			(size 0.519938 1.4986)
			(layers "F.Cu" "F.Mask" "F.Paste")
			(net "M_J_CPU0_SB_CB<1>")
		)
		(pad "99" smd rect
			(at -2.050034 25.07488 90)
			(size 0.519938 1.4986)
			(layers "F.Cu" "F.Mask" "F.Paste")
			(net "GND")
		)
		(pad "100" smd rect
			(at -2.050034 25.925018 90)
			(size 0.519938 1.4986)
			(layers "F.Cu" "F.Mask" "F.Paste")
			(net "M_J_CPU0_SB_DQ<0>")
		)
		(pad "101" smd rect
			(at -2.050034 26.774902 90)
			(size 0.519938 1.4986)
			(layers "F.Cu" "F.Mask" "F.Paste")
			(net "GND")
		)
		(pad "102" smd rect
			(at -2.050034 27.62504 90)
			(size 0.519938 1.4986)
			(layers "F.Cu" "F.Mask" "F.Paste")
			(net "M_J_CPU0_SB_DQ<1>")
		)
		(pad "103" smd rect
			(at -2.050034 28.474924 90)
			(size 0.519938 1.4986)
			(layers "F.Cu" "F.Mask" "F.Paste")
			(net "GND")
		)
		(pad "104" smd rect
			(at -2.050034 29.325062 90)
			(size 0.519938 1.4986)
			(layers "F.Cu" "F.Mask" "F.Paste")
			(net "M_J_CPU0_SB_DQS_DP<0>")
		)
		(pad "105" smd rect
			(at -2.050034 30.174946 90)
			(size 0.519938 1.4986)
			(layers "F.Cu" "F.Mask" "F.Paste")
			(net "M_J_CPU0_SB_DQS_DN<0>")
		)
		(pad "106" smd rect
			(at -2.050034 31.025084 90)
			(size 0.519938 1.4986)
			(layers "F.Cu" "F.Mask" "F.Paste")
			(net "GND")
		)
		(pad "107" smd rect
			(at -2.050034 31.874968 90)
			(size 0.519938 1.4986)
			(layers "F.Cu" "F.Mask" "F.Paste")
			(net "M_J_CPU0_SB_DQ<4>")
		)
		(pad "108" smd rect
			(at -2.050034 32.725106 90)
			(size 0.519938 1.4986)
			(layers "F.Cu" "F.Mask" "F.Paste")
			(net "GND")
		)
		(pad "109" smd rect
			(at -2.050034 33.57499 90)
			(size 0.519938 1.4986)
			(layers "F.Cu" "F.Mask" "F.Paste")
			(net "M_J_CPU0_SB_DQ<5>")
		)
		(pad "110" smd rect
			(at -2.050034 34.425128 90)
			(size 0.519938 1.4986)
			(layers "F.Cu" "F.Mask" "F.Paste")
			(net "GND")
		)
		(pad "111" smd rect
			(at -2.050034 35.275012 90)
			(size 0.519938 1.4986)
			(layers "F.Cu" "F.Mask" "F.Paste")
			(net "M_J_CPU0_SB_DQ<8>")
		)
		(pad "112" smd rect
			(at -2.050034 36.124896 90)
			(size 0.519938 1.4986)
			(layers "F.Cu" "F.Mask" "F.Paste")
			(net "GND")
		)
		(pad "113" smd rect
			(at -2.050034 36.975034 90)
			(size 0.519938 1.4986)
			(layers "F.Cu" "F.Mask" "F.Paste")
			(net "M_J_CPU0_SB_DQ<9>")
		)
		(pad "114" smd rect
			(at -2.050034 37.824918 90)
			(size 0.519938 1.4986)
			(layers "F.Cu" "F.Mask" "F.Paste")
			(net "GND")
		)
		(pad "115" smd rect
			(at -2.050034 38.675056 90)
			(size 0.519938 1.4986)
			(layers "F.Cu" "F.Mask" "F.Paste")
			(net "M_J_CPU0_SB_DQS_DP<1>")
		)
		(pad "116" smd rect
			(at -2.050034 39.52494 90)
			(size 0.519938 1.4986)
			(layers "F.Cu" "F.Mask" "F.Paste")
			(net "M_J_CPU0_SB_DQS_DN<1>")
		)
		(pad "117" smd rect
			(at -2.050034 40.375078 90)
			(size 0.519938 1.4986)
			(layers "F.Cu" "F.Mask" "F.Paste")
			(net "GND")
		)
		(pad "118" smd rect
			(at -2.050034 41.224962 90)
			(size 0.519938 1.4986)
			(layers "F.Cu" "F.Mask" "F.Paste")
			(net "M_J_CPU0_SB_DQ<12>")
		)
		(pad "119" smd rect
			(at -2.050034 42.0751 90)
			(size 0.519938 1.4986)
			(layers "F.Cu" "F.Mask" "F.Paste")
			(net "GND")
		)
		(pad "120" smd rect
			(at -2.050034 42.924984 90)
			(size 0.519938 1.4986)
			(layers "F.Cu" "F.Mask" "F.Paste")
			(net "M_J_CPU0_SB_DQ<13>")
		)
		(pad "121" smd rect
			(at -2.050034 43.775122 90)
			(size 0.519938 1.4986)
			(layers "F.Cu" "F.Mask" "F.Paste")
			(net "GND")
		)
		(pad "122" smd rect
			(at -2.050034 44.625006 90)
			(size 0.519938 1.4986)
			(layers "F.Cu" "F.Mask" "F.Paste")
			(net "M_J_CPU0_SB_DQ<16>")
		)
		(pad "123" smd rect
			(at -2.050034 45.47489 90)
			(size 0.519938 1.4986)
			(layers "F.Cu" "F.Mask" "F.Paste")
			(net "GND")
		)
		(pad "124" smd rect
			(at -2.050034 46.325028 90)
			(size 0.519938 1.4986)
			(layers "F.Cu" "F.Mask" "F.Paste")
			(net "M_J_CPU0_SB_DQ<17>")
		)
		(pad "125" smd rect
			(at -2.050034 47.174912 90)
			(size 0.519938 1.4986)
			(layers "F.Cu" "F.Mask" "F.Paste")
			(net "GND")
		)
		(pad "126" smd rect
			(at -2.050034 48.02505 90)
			(size 0.519938 1.4986)
			(layers "F.Cu" "F.Mask" "F.Paste")
			(net "M_J_CPU0_SB_DQS_DP<2>")
		)
		(pad "127" smd rect
			(at -2.050034 48.874934 90)
			(size 0.519938 1.4986)
			(layers "F.Cu" "F.Mask" "F.Paste")
			(net "M_J_CPU0_SB_DQS_DN<2>")
		)
		(pad "128" smd rect
			(at -2.050034 49.725072 90)
			(size 0.519938 1.4986)
			(layers "F.Cu" "F.Mask" "F.Paste")
			(net "GND")
		)
		(pad "129" smd rect
			(at -2.050034 50.574956 90)
			(size 0.519938 1.4986)
			(layers "F.Cu" "F.Mask" "F.Paste")
			(net "M_J_CPU0_SB_DQ<20>")
		)
		(pad "130" smd rect
			(at -2.050034 51.425094 90)
			(size 0.519938 1.4986)
			(layers "F.Cu" "F.Mask" "F.Paste")
			(net "GND")
		)
		(pad "131" smd rect
			(at -2.050034 52.274978 90)
			(size 0.519938 1.4986)
			(layers "F.Cu" "F.Mask" "F.Paste")
			(net "M_J_CPU0_SB_DQ<21>")
		)
		(pad "132" smd rect
			(at -2.050034 53.125116 90)
			(size 0.519938 1.4986)
			(layers "F.Cu" "F.Mask" "F.Paste")
			(net "GND")
		)
		(pad "133" smd rect
			(at -2.050034 53.975 90)
			(size 0.519938 1.4986)
			(layers "F.Cu" "F.Mask" "F.Paste")
			(net "M_J_CPU0_SB_DQ<24>")
		)
		(pad "134" smd rect
			(at -2.050034 54.824884 90)
			(size 0.519938 1.4986)
			(layers "F.Cu" "F.Mask" "F.Paste")
			(net "GND")
		)
		(pad "135" smd rect
			(at -2.050034 55.675022 90)
			(size 0.519938 1.4986)
			(layers "F.Cu" "F.Mask" "F.Paste")
			(net "M_J_CPU0_SB_DQ<25>")
		)
		(pad "136" smd rect
			(at -2.050034 56.524906 90)
			(size 0.519938 1.4986)
			(layers "F.Cu" "F.Mask" "F.Paste")
			(net "GND")
		)
		(pad "137" smd rect
			(at -2.050034 57.375044 90)
			(size 0.519938 1.4986)
			(layers "F.Cu" "F.Mask" "F.Paste")
			(net "M_J_CPU0_SB_DQS_DP<3>")
		)
	)
)
